#ISCELL
  mstr_misc dns *
  *
#ISCELL
  mstr_symbols design_note *
  *
#ISCELL
  mstr_symbols intel_corp_bpage *
  *
#ISCELL
  mstr_standard offpage *
  page201_i1
#ISCELL
  mstr_standard offpage *
  page201_i10
#CELL
  mstr_discrete res *
  page201_i102
#CELL
  mstr_discrete res *
  page201_i103
#CELL
  mstr_discrete res *
  page201_i109
#ISCELL
  mstr_standard offpage *
  page201_i11
#CELL
  mstr_discrete res *
  page201_i110
#CELL
  mstr_discrete res *
  page201_i111
#ISCELL
  mstr_symbols p3v3_stby *
  page201_i112
#ISCELL
  mstr_symbols p3v3_stby *
  page201_i113
#ISCELL
  mstr_symbols p3v3_stby *
  page201_i115
#CELL
  mstr_discrete res *
  page201_i116
#ISCELL
  mstr_standard offpage *
  page201_i118
#ISCELL
  mstr_standard offpage *
  page201_i12
#CELL
  mstr_discrete res *
  page201_i120
#CELL
  mstr_discrete res *
  page201_i121
#CELL
  mstr_conn conn3_c95678002 *
  page201_i122
#ISCELL
  mstr_symbols gnd *
  page201_i123
#CELL
  mstr_discrete res *
  page201_i124
#CELL
  mstr_discrete cap *
  page201_i125
#ISCELL
  mstr_symbols gnd *
  page201_i126
#CELL
  mstr_discrete res *
  page201_i127
#CELL
  mstr_discrete res *
  page201_i128
#CELL
  mstr_discrete res *
  page201_i131
#CELL
  mstr_discrete res *
  page201_i132
#CELL
  mstr_discrete res *
  page201_i139
#ISCELL
  mstr_standard offpage *
  page201_i14
#ISCELL
  mstr_standard offpage *
  page201_i146
#CELL
  mstr_discrete res *
  page201_i147
#CELL
  mstr_discrete res *
  page201_i148
#CELL
  mstr_discrete res *
  page201_i149
#ISCELL
  mstr_standard offpage *
  page201_i15
#CELL
  mstr_discrete res *
  page201_i150
#ISCELL
  mstr_standard offpage *
  page201_i152
#CELL
  mstr_discrete res *
  page201_i154
#CELL
  mstr_controller pxe1610b *
  page201_i155
#ISCELL
  mstr_standard offpage *
  page201_i17
#ISCELL
  mstr_symbols pvccio_cpu0 *
  page201_i18
#CELL
  mstr_discrete res *
  page201_i19
#ISCELL
  mstr_standard offpage *
  page201_i2
#CELL
  mstr_discrete res *
  page201_i20
#CELL
  mstr_discrete res *
  page201_i22
#CELL
  mstr_discrete res *
  page201_i25
#CELL
  mstr_discrete res *
  page201_i26
#CELL
  mstr_discrete res *
  page201_i27
#CELL
  mstr_discrete res *
  page201_i28
#ISCELL
  mstr_symbols gnd *
  page201_i29
#ISCELL
  mstr_standard offpage *
  page201_i3
#CELL
  dev_discrete cap_a *
  page201_i30
#CELL
  mstr_discrete res *
  page201_i31
#CELL
  dev_discrete cap_a *
  page201_i32
#ISCELL
  mstr_symbols gnd *
  page201_i33
#ISCELL
  mstr_symbols gnd *
  page201_i35
#ISCELL
  mstr_symbols gnd *
  page201_i36
#CELL
  dev_discrete cap_a *
  page201_i37
#ISCELL
  mstr_symbols gnd *
  page201_i38
#CELL
  dev_discrete cap_a *
  page201_i39
#ISCELL
  mstr_standard offpage *
  page201_i4
#CELL
  mstr_discrete res *
  page201_i40
#ISCELL
  mstr_symbols gnd *
  page201_i48
#ISCELL
  mstr_standard offpage *
  page201_i5
#ISCELL
  mstr_symbols gnd *
  page201_i50
#ISCELL
  mstr_symbols pvccio_cpu0 *
  page201_i51
#CELL
  mstr_discrete res *
  page201_i52
#ISCELL
  mstr_symbols vcc_core *
  page201_i53
#CELL
  mstr_discrete res *
  page201_i54
#CELL
  mstr_discrete res *
  page201_i55
#CELL
  mstr_discrete res *
  page201_i56
#ISCELL
  mstr_symbols gnd *
  page201_i58
#ISCELL
  mstr_standard offpage *
  page201_i6
#CELL
  mstr_discrete cap *
  page201_i60
#ISCELL
  mstr_symbols gnd *
  page201_i61
#CELL
  mstr_discrete cap *
  page201_i64
#CELL
  mstr_discrete cap *
  page201_i66
#ISCELL
  mstr_symbols gnd *
  page201_i67
#CELL
  mstr_discrete cap *
  page201_i68
#ISCELL
  mstr_symbols gnd *
  page201_i69
#ISCELL
  mstr_standard offpage *
  page201_i7
#CELL
  mstr_discrete cap *
  page201_i70
#ISCELL
  mstr_standard offpage *
  page201_i73
#ISCELL
  mstr_standard offpage *
  page201_i74
#ISCELL
  mstr_standard offpage *
  page201_i75
#ISCELL
  mstr_standard offpage *
  page201_i76
#ISCELL
  mstr_standard offpage *
  page201_i77
#ISCELL
  mstr_standard offpage *
  page201_i78
#ISCELL
  mstr_standard offpage *
  page201_i79
#ISCELL
  mstr_standard offpage *
  page201_i8
#ISCELL
  mstr_standard offpage *
  page201_i80
#ISCELL
  mstr_standard offpage *
  page201_i82
#ISCELL
  mstr_standard offpage *
  page201_i83
#ISCELL
  mstr_standard offpage *
  page201_i84
#ISCELL
  mstr_standard offpage *
  page201_i85
#ISCELL
  mstr_standard offpage *
  page201_i87
#ISCELL
  mstr_standard offpage *
  page201_i88
#ISCELL
  mstr_standard offpage *
  page201_i89
#ISCELL
  mstr_standard offpage *
  page201_i9
#ISCELL
  mstr_standard offpage *
  page201_i90
#ISCELL
  mstr_standard offpage *
  page201_i91
#ISCELL
  mstr_standard offpage *
  page201_i92
#ISCELL
  mstr_standard offpage *
  page201_i93
#ISCELL
  mstr_standard offpage *
  page201_i94
#ISCELL
  mstr_standard offpage *
  page201_i95
#ISCELL
  mstr_standard offpage *
  page201_i96
#ISCELL
  mstr_standard offpage *
  page201_i97
#CELL
  mstr_discrete res *
  page201_i98
